# BASEBOARD_FAB2 (Tioga Pass) — schematic netlist excerpt (pin names and nets, part order shuffled) for the footprints in the layout excerpt that follows; sources: Cadence DE-HDL packaged netlist, KiCad conversion of Wiwynn_Tioga_Pass_MB.brd

C1G19  CAP_A  0.01UF 25V 10% X7R  pkg 0402V  page 82 : A = M_J_VREF ; B = GND
C9G16  CAP  4700PF 50V 10% EMPTY  pkg 0402LF  page 141 : A = NIC_SET_P_MDI_2_DP ; B = NIC_MDI_MNG_TX_DP
R8G10  RES  0.0 5% CHIP  pkg 0402  page 189 : A = JTAG_BMC_TRST_N ; B = JTAG_TRST_N

(kicad_pcb
	(version 20260206)
	(generator "pcbnew")
	(generator_version "10.0")
	(general
		(thickness 1.6)
		(legacy_teardrops no)
	)
	(paper "A4")
	(title_block
		(title "Wiwynn_Tioga_Pass_MB.brd")
		(comment 1 "Tioga Pass / footprints 658-660 of 4770")
	)
	(layers
		(0 "F.Cu" signal "TOP")
		(4 "In1.Cu" signal "L2GND")
		(6 "In2.Cu" signal "L3")
		(8 "In3.Cu" signal "L4GND")
		(10 "In4.Cu" signal "L5")
		(12 "In5.Cu" signal "L6GND")
		(14 "In6.Cu" signal "L7VCC")
		(16 "In7.Cu" signal "L8VCC")
		(18 "In8.Cu" signal "L9GND")
		(20 "In9.Cu" signal "L10")
		(22 "In10.Cu" signal "L11GND")
		(24 "In11.Cu" signal "L12")
		(26 "In12.Cu" signal "L13GND")
		(2 "B.Cu" signal "BOTTOM")
		(9 "F.Adhes" user "F.Adhesive")
		(11 "B.Adhes" user "B.Adhesive")
		(13 "F.Paste" user "Package Geometry/Pastemask Top")
		(15 "B.Paste" user "Package Geometry/Pastemask Bottom")
		(5 "F.SilkS" user "Ref Des/Silkscreen Top")
		(7 "B.SilkS" user "Ref Des/Silkscreen Bottom")
		(1 "F.Mask" user "Board Geometry/Soldermask Top")
		(3 "B.Mask" user "Board Geometry/Soldermask Bottom")
		(17 "Dwgs.User" user "User.Drawings")
		(19 "Cmts.User" user "User.Comments")
		(21 "Eco1.User" user "User.Eco1")
		(23 "Eco2.User" user "User.Eco2")
		(25 "Edge.Cuts" user "Board Geometry/Outline")
		(27 "Margin" user)
		(31 "F.CrtYd" user "Package Geometry/Place Bound Top")
		(29 "B.CrtYd" user "Package Geometry/Place Bound Bottom")
		(35 "F.Fab" user "Ref Des/Assembly Top")
		(33 "B.Fab" user "Ref Des/Assembly Bottom")
	)
	(footprint ""
		(layer "F.Cu")
		(at 30.579568 -3.321812 90)
		(property "Reference" "C1G19"
			(at 0 0 90)
			(layer "F.SilkS")
			(hide yes)
			(effects
				(font
					(size 1.27 1.27)
				)
			)
		)
		(property "Value" ""
			(at 0 0 90)
			(layer "F.Fab")
			(effects
				(font
					(size 1.27 1.27)
				)
			)
		)
		(duplicate_pad_numbers_are_jumpers no)
		(fp_poly
			(pts
				(xy 0.3048 -0.1016) (xy 0.3048 0.9906) (xy -0.3048 0.9906) (xy -0.3048 -0.1016)
			)
			(stroke
				(width 0)
				(type default)
			)
			(fill no)
			(layer "F.CrtYd")
		)
		(fp_line
			(start 0.3048 -0.1016)
			(end -0.3048 -0.1016)
			(stroke
				(width 0.1)
				(type default)
			)
			(layer "F.Fab")
		)
		(fp_line
			(start -0.3048 -0.1016)
			(end -0.3048 0.9906)
			(stroke
				(width 0.1)
				(type default)
			)
			(layer "F.Fab")
		)
		(fp_line
			(start 0.3048 0.9906)
			(end 0.3048 -0.1016)
			(stroke
				(width 0.1)
				(type default)
			)
			(layer "F.Fab")
		)
		(fp_line
			(start -0.3048 0.9906)
			(end 0.3048 0.9906)
			(stroke
				(width 0.1)
				(type default)
			)
			(layer "F.Fab")
		)
		(pad "1" smd rect
			(at 0 0 90)
			(size 0.508 0.508)
			(layers "F.Cu" "F.Mask" "F.Paste")
			(net "M_J_VREF")
		)
		(pad "2" smd rect
			(at 0 0.889 90)
			(size 0.508 0.508)
			(layers "F.Cu" "F.Mask" "F.Paste")
			(net "GND")
		)
		(zone
			(layer "F.Cu")
			(hatch none 0.5)
			(connect_pads
				(clearance 0)
			)
			(min_thickness 0.25)
			(keepout
				(tracks allowed)
				(vias not_allowed)
				(pads allowed)
				(copperpour not_allowed)
				(footprints allowed)
			)
			(placement
				(enabled no)
				(sheetname "")
			)
			(fill
				(thermal_gap 0.5)
				(thermal_bridge_width 0.5)
				(island_removal_mode 0)
			)
			(polygon
				(pts
					(xy 30.833568 -3.067812) (xy 30.833568 -3.575812) (xy 31.214568 -3.575812) (xy 31.214568 -3.067812)
				)
			)
		)
		(zone
			(layer "F.Cu")
			(hatch none 0.5)
			(connect_pads
				(clearance 0)
			)
			(min_thickness 0.25)
			(keepout
				(tracks not_allowed)
				(vias allowed)
				(pads allowed)
				(copperpour not_allowed)
				(footprints allowed)
			)
			(placement
				(enabled no)
				(sheetname "")
			)
			(fill
				(thermal_gap 0.5)
				(thermal_bridge_width 0.5)
				(island_removal_mode 0)
			)
			(polygon
				(pts
					(xy 31.214568 -3.067812) (xy 31.214568 -3.575812) (xy 30.833568 -3.575812) (xy 30.833568 -3.067812)
				)
			)
		)
	)
	(footprint ""
		(layer "F.Cu")
		(at 392.049 -0.254)
		(property "Reference" "R8G10"
			(at 0 0 0)
			(layer "F.SilkS")
			(hide yes)
			(effects
				(font
					(size 1.27 1.27)
				)
			)
		)
		(property "Value" ""
			(at 0 0 0)
			(layer "F.Fab")
			(effects
				(font
					(size 1.27 1.27)
				)
			)
		)
		(duplicate_pad_numbers_are_jumpers no)
		(fp_poly
			(pts
				(xy -0.2794 -0.1016) (xy 0.2794 -0.1016) (xy 0.2794 0.9906) (xy -0.2794 0.9906)
			)
			(stroke
				(width 0)
				(type default)
			)
			(fill no)
			(layer "F.CrtYd")
		)
		(fp_line
			(start -0.2794 -0.1016)
			(end -0.2794 0.9906)
			(stroke
				(width 0.1)
				(type default)
			)
			(layer "F.Fab")
		)
		(fp_line
			(start -0.2794 0.9906)
			(end 0.2794 0.9906)
			(stroke
				(width 0.1)
				(type default)
			)
			(layer "F.Fab")
		)
		(fp_line
			(start 0.2794 -0.1016)
			(end -0.2794 -0.1016)
			(stroke
				(width 0.1)
				(type default)
			)
			(layer "F.Fab")
		)
		(fp_line
			(start 0.2794 0.9906)
			(end 0.2794 -0.1016)
			(stroke
				(width 0.1)
				(type default)
			)
			(layer "F.Fab")
		)
		(pad "1" smd rect
			(at 0 0)
			(size 0.508 0.508)
			(layers "F.Cu" "F.Mask" "F.Paste")
			(net "JTAG_BMC_TRST_N")
		)
		(pad "2" smd rect
			(at 0 0.889)
			(size 0.508 0.508)
			(layers "F.Cu" "F.Mask" "F.Paste")
			(net "JTAG_TRST_N")
		)
		(zone
			(layer "F.Cu")
			(hatch none 0.5)
			(connect_pads
				(clearance 0)
			)
			(min_thickness 0.25)
			(keepout
				(tracks allowed)
				(vias not_allowed)
				(pads allowed)
				(copperpour not_allowed)
				(footprints allowed)
			)
			(placement
				(enabled no)
				(sheetname "")
			)
			(fill
				(thermal_gap 0.5)
				(thermal_bridge_width 0.5)
				(island_removal_mode 0)
			)
			(polygon
				(pts
					(xy 391.795 0) (xy 392.303 0) (xy 392.303 0.381) (xy 391.795 0.381)
				)
			)
		)
		(zone
			(layer "F.Cu")
			(hatch none 0.5)
			(connect_pads
				(clearance 0)
			)
			(min_thickness 0.25)
			(keepout
				(tracks not_allowed)
				(vias allowed)
				(pads allowed)
				(copperpour not_allowed)
				(footprints allowed)
			)
			(placement
				(enabled no)
				(sheetname "")
			)
			(fill
				(thermal_gap 0.5)
				(thermal_bridge_width 0.5)
				(island_removal_mode 0)
			)
			(polygon
				(pts
					(xy 391.795 0.381) (xy 392.303 0.381) (xy 392.303 0) (xy 391.795 0)
				)
			)
		)
	)
	(footprint ""
		(layer "F.Cu")
		(at 480.842574 4.65709 90)
		(property "Reference" "C9G16"
			(at 0 0 90)
			(layer "F.SilkS")
			(hide yes)
			(effects
				(font
					(size 1.27 1.27)
				)
			)
		)
		(property "Value" ""
			(at 0 0 90)
			(layer "F.Fab")
			(effects
				(font
					(size 1.27 1.27)
				)
			)
		)
		(duplicate_pad_numbers_are_jumpers no)
		(fp_poly
			(pts
				(xy 0.3048 -0.1016) (xy 0.3048 0.9906) (xy -0.3048 0.9906) (xy -0.3048 -0.1016)
			)
			(stroke
				(width 0)
				(type default)
			)
			(fill no)
			(layer "F.CrtYd")
		)
		(fp_line
			(start 0.3048 -0.1016)
			(end -0.3048 -0.1016)
			(stroke
				(width 0.1)
				(type default)
			)
			(layer "F.Fab")
		)
		(fp_line
			(start -0.3048 -0.1016)
			(end -0.3048 0.9906)
			(stroke
				(width 0.1)
				(type default)
			)
			(layer "F.Fab")
		)
		(fp_line
			(start 0.3048 0.9906)
			(end 0.3048 -0.1016)
			(stroke
				(width 0.1)
				(type default)
			)
			(layer "F.Fab")
		)
		(fp_line
			(start -0.3048 0.9906)
			(end 0.3048 0.9906)
			(stroke
				(width 0.1)
				(type default)
			)
			(layer "F.Fab")
		)
		(pad "1" smd rect
			(at 0 0 90)
			(size 0.508 0.508)
			(layers "F.Cu" "F.Mask" "F.Paste")
			(net "NIC_SET_P_MDI_2_DP")
		)
		(pad "2" smd rect
			(at 0 0.889 90)
			(size 0.508 0.508)
			(layers "F.Cu" "F.Mask" "F.Paste")
			(net "NIC_MDI_MNG_TX_DP")
		)
		(zone
			(layer "F.Cu")
			(hatch none 0.5)
			(connect_pads
				(clearance 0)
			)
			(min_thickness 0.25)
			(keepout
				(tracks allowed)
				(vias not_allowed)
				(pads allowed)
				(copperpour not_allowed)
				(footprints allowed)
			)
			(placement
				(enabled no)
				(sheetname "")
			)
			(fill
				(thermal_gap 0.5)
				(thermal_bridge_width 0.5)
				(island_removal_mode 0)
			)
			(polygon
				(pts
					(xy 481.096574 4.91109) (xy 481.096574 4.40309) (xy 481.477574 4.40309) (xy 481.477574 4.91109)
				)
			)
		)
		(zone
			(layer "F.Cu")
			(hatch none 0.5)
			(connect_pads
				(clearance 0)
			)
			(min_thickness 0.25)
			(keepout
				(tracks not_allowed)
				(vias allowed)
				(pads allowed)
				(copperpour not_allowed)
				(footprints allowed)
			)
			(placement
				(enabled no)
				(sheetname "")
			)
			(fill
				(thermal_gap 0.5)
				(thermal_bridge_width 0.5)
				(island_removal_mode 0)
			)
			(polygon
				(pts
					(xy 481.477574 4.91109) (xy 481.477574 4.40309) (xy 481.096574 4.40309) (xy 481.096574 4.91109)
				)
			)
		)
	)
)
